# BASEBOARD_FAB2 (Tioga Pass) — schematic netlist excerpt (pin names and nets, part order shuffled) for the footprints in the layout excerpt that follows; sources: Cadence DE-HDL packaged netlist, KiCad conversion of Wiwynn_Tioga_Pass_MB.brd

C1G21  CAP  1000PF 50V 10% X7R  pkg 0402LF  page 223 : A = PWRGD_PVDDQ_GHJ_R ; B = GND
R6W42  RES  4.75K 1% EMPTY  pkg 0402  page 164 : A = P3V3_STBY ; B = PCA9554_A2
C2G9  CAP_A  47UF 4V 20% X5R  pkg 0603V  page 225 : A = PVDDQ_GHJ ; B = GND

(kicad_pcb
	(version 20260206)
	(generator "pcbnew")
	(generator_version "10.0")
	(general
		(thickness 1.6)
		(legacy_teardrops no)
	)
	(paper "A4")
	(title_block
		(title "Wiwynn_Tioga_Pass_MB.brd")
		(comment 1 "Tioga Pass / footprints 1390-1392 of 4770")
	)
	(layers
		(0 "F.Cu" signal "TOP")
		(4 "In1.Cu" signal "L2GND")
		(6 "In2.Cu" signal "L3")
		(8 "In3.Cu" signal "L4GND")
		(10 "In4.Cu" signal "L5")
		(12 "In5.Cu" signal "L6GND")
		(14 "In6.Cu" signal "L7VCC")
		(16 "In7.Cu" signal "L8VCC")
		(18 "In8.Cu" signal "L9GND")
		(20 "In9.Cu" signal "L10")
		(22 "In10.Cu" signal "L11GND")
		(24 "In11.Cu" signal "L12")
		(26 "In12.Cu" signal "L13GND")
		(2 "B.Cu" signal "BOTTOM")
		(9 "F.Adhes" user "F.Adhesive")
		(11 "B.Adhes" user "B.Adhesive")
		(13 "F.Paste" user "Package Geometry/Pastemask Top")
		(15 "B.Paste" user "Package Geometry/Pastemask Bottom")
		(5 "F.SilkS" user "Ref Des/Silkscreen Top")
		(7 "B.SilkS" user "Ref Des/Silkscreen Bottom")
		(1 "F.Mask" user "Board Geometry/Soldermask Top")
		(3 "B.Mask" user "Board Geometry/Soldermask Bottom")
		(17 "Dwgs.User" user "User.Drawings")
		(19 "Cmts.User" user "User.Comments")
		(21 "Eco1.User" user "User.Eco1")
		(23 "Eco2.User" user "User.Eco2")
		(25 "Edge.Cuts" user "Board Geometry/Outline")
		(27 "Margin" user)
		(31 "F.CrtYd" user "Package Geometry/Place Bound Top")
		(29 "B.CrtYd" user "Package Geometry/Place Bound Bottom")
		(35 "F.Fab" user "Ref Des/Assembly Top")
		(33 "B.Fab" user "Ref Des/Assembly Bottom")
	)
	(footprint ""
		(layer "F.Cu")
		(at 80.757268 -3.3528 -90)
		(property "Reference" "C2G9"
			(at 1.848866 0.752348 270)
			(unlocked yes)
			(layer "F.SilkS")
			(effects
				(font
					(size 1.27 0.9652)
					(thickness 0.1524)
				)
			)
		)
		(property "Value" ""
			(at 0 0 270)
			(layer "F.Fab")
			(effects
				(font
					(size 1.27 1.27)
				)
			)
		)
		(duplicate_pad_numbers_are_jumpers no)
		(fp_rect
			(start -0.500126 1.598422)
			(end 0.500126 -0.201422)
			(stroke
				(width 0)
				(type default)
			)
			(fill no)
			(layer "F.CrtYd")
		)
		(fp_line
			(start -0.500126 1.598422)
			(end -0.500126 -0.201422)
			(stroke
				(width 0.1)
				(type default)
			)
			(layer "F.Fab")
		)
		(fp_line
			(start 0.500126 1.598422)
			(end -0.500126 1.598422)
			(stroke
				(width 0.1)
				(type default)
			)
			(layer "F.Fab")
		)
		(fp_line
			(start -0.500126 -0.201422)
			(end 0.500126 -0.201422)
			(stroke
				(width 0.1)
				(type default)
			)
			(layer "F.Fab")
		)
		(fp_line
			(start 0.500126 -0.201422)
			(end 0.500126 1.598422)
			(stroke
				(width 0.1)
				(type default)
			)
			(layer "F.Fab")
		)
		(pad "1" smd rect
			(at 0 0 180)
			(size 0.889 0.9906)
			(layers "F.Cu" "F.Mask" "F.Paste")
			(net "PVDDQ_GHJ")
		)
		(pad "2" smd rect
			(at 0 1.397 180)
			(size 0.889 0.9906)
			(layers "F.Cu" "F.Mask" "F.Paste")
			(net "GND")
		)
		(zone
			(layer "F.Cu")
			(hatch none 0.5)
			(connect_pads
				(clearance 0)
			)
			(min_thickness 0.25)
			(keepout
				(tracks not_allowed)
				(vias allowed)
				(pads allowed)
				(copperpour not_allowed)
				(footprints allowed)
			)
			(placement
				(enabled no)
				(sheetname "")
			)
			(fill
				(thermal_gap 0.5)
				(thermal_bridge_width 0.5)
				(island_removal_mode 0)
			)
			(polygon
				(pts
					(xy 79.804768 -3.8481) (xy 79.804768 -2.8575) (xy 80.312768 -2.8575) (xy 80.312768 -3.8481)
				)
			)
		)
		(zone
			(layer "F.Cu")
			(hatch none 0.5)
			(connect_pads
				(clearance 0)
			)
			(min_thickness 0.25)
			(keepout
				(tracks allowed)
				(vias not_allowed)
				(pads allowed)
				(copperpour not_allowed)
				(footprints allowed)
			)
			(placement
				(enabled no)
				(sheetname "")
			)
			(fill
				(thermal_gap 0.5)
				(thermal_bridge_width 0.5)
				(island_removal_mode 0)
			)
			(polygon
				(pts
					(xy 79.804768 -3.8481) (xy 79.804768 -2.8575) (xy 80.312768 -2.8575) (xy 80.312768 -3.8481)
				)
			)
		)
	)
	(footprint ""
		(layer "F.Cu")
		(at 13.640816 -1.197864 90)
		(property "Reference" "C1G21"
			(at 0 0 90)
			(layer "F.SilkS")
			(hide yes)
			(effects
				(font
					(size 1.27 1.27)
				)
			)
		)
		(property "Value" ""
			(at 0 0 90)
			(layer "F.Fab")
			(effects
				(font
					(size 1.27 1.27)
				)
			)
		)
		(duplicate_pad_numbers_are_jumpers no)
		(fp_poly
			(pts
				(xy 0.3048 -0.1016) (xy 0.3048 0.9906) (xy -0.3048 0.9906) (xy -0.3048 -0.1016)
			)
			(stroke
				(width 0)
				(type default)
			)
			(fill no)
			(layer "F.CrtYd")
		)
		(fp_line
			(start 0.3048 -0.1016)
			(end -0.3048 -0.1016)
			(stroke
				(width 0.1)
				(type default)
			)
			(layer "F.Fab")
		)
		(fp_line
			(start -0.3048 -0.1016)
			(end -0.3048 0.9906)
			(stroke
				(width 0.1)
				(type default)
			)
			(layer "F.Fab")
		)
		(fp_line
			(start 0.3048 0.9906)
			(end 0.3048 -0.1016)
			(stroke
				(width 0.1)
				(type default)
			)
			(layer "F.Fab")
		)
		(fp_line
			(start -0.3048 0.9906)
			(end 0.3048 0.9906)
			(stroke
				(width 0.1)
				(type default)
			)
			(layer "F.Fab")
		)
		(pad "1" smd rect
			(at 0 0 90)
			(size 0.508 0.508)
			(layers "F.Cu" "F.Mask" "F.Paste")
			(net "PWRGD_PVDDQ_GHJ_R")
		)
		(pad "2" smd rect
			(at 0 0.889 90)
			(size 0.508 0.508)
			(layers "F.Cu" "F.Mask" "F.Paste")
			(net "GND")
		)
		(zone
			(layer "F.Cu")
			(hatch none 0.5)
			(connect_pads
				(clearance 0)
			)
			(min_thickness 0.25)
			(keepout
				(tracks allowed)
				(vias not_allowed)
				(pads allowed)
				(copperpour not_allowed)
				(footprints allowed)
			)
			(placement
				(enabled no)
				(sheetname "")
			)
			(fill
				(thermal_gap 0.5)
				(thermal_bridge_width 0.5)
				(island_removal_mode 0)
			)
			(polygon
				(pts
					(xy 13.894816 -0.943864) (xy 13.894816 -1.451864) (xy 14.275816 -1.451864) (xy 14.275816 -0.943864)
				)
			)
		)
		(zone
			(layer "F.Cu")
			(hatch none 0.5)
			(connect_pads
				(clearance 0)
			)
			(min_thickness 0.25)
			(keepout
				(tracks not_allowed)
				(vias allowed)
				(pads allowed)
				(copperpour not_allowed)
				(footprints allowed)
			)
			(placement
				(enabled no)
				(sheetname "")
			)
			(fill
				(thermal_gap 0.5)
				(thermal_bridge_width 0.5)
				(island_removal_mode 0)
			)
			(polygon
				(pts
					(xy 14.275816 -0.943864) (xy 14.275816 -1.451864) (xy 13.894816 -1.451864) (xy 13.894816 -0.943864)
				)
			)
		)
	)
	(footprint ""
		(layer "F.Cu")
		(at 433.832 -14.224 180)
		(property "Reference" "R6W42"
			(at -0.8382 -0.67818 180)
			(unlocked yes)
			(layer "F.SilkS")
			(effects
				(font
					(size 0.4064 0.254)
					(thickness 0.1524)
				)
				(justify left)
			)
		)
		(property "Value" ""
			(at 0 0 180)
			(layer "F.Fab")
			(effects
				(font
					(size 1.27 1.27)
				)
			)
		)
		(duplicate_pad_numbers_are_jumpers no)
		(fp_poly
			(pts
				(xy -0.2794 -0.1016) (xy 0.2794 -0.1016) (xy 0.2794 0.9906) (xy -0.2794 0.9906)
			)
			(stroke
				(width 0)
				(type default)
			)
			(fill no)
			(layer "F.CrtYd")
		)
		(fp_line
			(start 0.2794 0.9906)
			(end 0.2794 -0.1016)
			(stroke
				(width 0.1)
				(type default)
			)
			(layer "F.Fab")
		)
		(fp_line
			(start 0.2794 -0.1016)
			(end -0.2794 -0.1016)
			(stroke
				(width 0.1)
				(type default)
			)
			(layer "F.Fab")
		)
		(fp_line
			(start -0.2794 0.9906)
			(end 0.2794 0.9906)
			(stroke
				(width 0.1)
				(type default)
			)
			(layer "F.Fab")
		)
		(fp_line
			(start -0.2794 -0.1016)
			(end -0.2794 0.9906)
			(stroke
				(width 0.1)
				(type default)
			)
			(layer "F.Fab")
		)
		(pad "1" smd rect
			(at 0 0 180)
			(size 0.508 0.508)
			(layers "F.Cu" "F.Mask" "F.Paste")
			(net "P3V3_STBY")
		)
		(pad "2" smd rect
			(at 0 0.889 180)
			(size 0.508 0.508)
			(layers "F.Cu" "F.Mask" "F.Paste")
			(net "PCA9554_A2")
		)
		(zone
			(layer "F.Cu")
			(hatch none 0.5)
			(connect_pads
				(clearance 0)
			)
			(min_thickness 0.25)
			(keepout
				(tracks not_allowed)
				(vias allowed)
				(pads allowed)
				(copperpour not_allowed)
				(footprints allowed)
			)
			(placement
				(enabled no)
				(sheetname "")
			)
			(fill
				(thermal_gap 0.5)
				(thermal_bridge_width 0.5)
				(island_removal_mode 0)
			)
			(polygon
				(pts
					(xy 434.086 -14.859) (xy 433.578 -14.859) (xy 433.578 -14.478) (xy 434.086 -14.478)
				)
			)
		)
		(zone
			(layer "F.Cu")
			(hatch none 0.5)
			(connect_pads
				(clearance 0)
			)
			(min_thickness 0.25)
			(keepout
				(tracks allowed)
				(vias not_allowed)
				(pads allowed)
				(copperpour not_allowed)
				(footprints allowed)
			)
			(placement
				(enabled no)
				(sheetname "")
			)
			(fill
				(thermal_gap 0.5)
				(thermal_bridge_width 0.5)
				(island_removal_mode 0)
			)
			(polygon
				(pts
					(xy 434.086 -14.478) (xy 433.578 -14.478) (xy 433.578 -14.859) (xy 434.086 -14.859)
				)
			)
		)
	)
)
